FILE_TYPE = CONNECTIVITY;
{Allegro Design Entry HDL 17.2-2016 S081 (4005846) 1/11/2022}
"PAGE_NUMBER" = 47;
0"NC";
1"PVNN_TERM_CPU1\g";
2"NC_CPU1_DDR45_VIEWDIG1"CDS_PHYS_NET_NAME"VSENSE_PVCCFA_EHV_CPU1_DP";
3"NC_CPU1_DDR67_VIEWDIG0";
4"NC_CPU1_DDR67_VIEWDIG1"CDS_PHYS_NET_NAME"VSENSE_PVCCFA_EHV_CPU1_DP";
5"H_PMAX_TRIGGER_IO_CPU1";
6"NC_CPU1_DDR01_VIEWDIG0";
7"NC_CPU1_DDR45_VIEWDIG0";
8"NC_CPU1_DDR23_VIEWDIG0";
9"NC_CPU1_DDR23_VIEWDIG1"CDS_PHYS_NET_NAME"VSENSE_PVCCFA_EHV_CPU1_DP";
10"NC_CPU1_DDR01_VIEWDIG1"CDS_PHYS_NET_NAME"VSENSE_PVCCFA_EHV_CPU1_DP";
11"VSENSE_PVCCD_HV_CPU1_DP";
12"VSENSE_PVCCFA_EHV_FIVRA_CPU1_DP";
13"VSENSE_PVCCFA_EHV_CPU1_DP";
14"VSENSE_PVCCINFAON_CPU1_DP";
15"VSENSE_PVCCIN_CPU1_DP";
16"VSENSE_PVCCD_HV_CPU1_DN";
17"VSENSE_PVCCFA_EHV_FIVRA_CPU1_DN";
18"VSENSE_PVCCFA_EHV_CPU1_DN";
19"VSENSE_PVCCINFAON_CPU1_DN";
20"VSENSE_PVCCIN_CPU1_DN";
21"NC_CPU1_LGSSPARE4";
22"NC_CPU1_THERMADA";
23"NC_CPU1_THERMADC";
24"TP_CPU1_A0_DEBUG_EN";
25"NC_CPU1_LGSSPARE0";
26"NC_CPU1_LGSSPARE5";
27"NC_CPU1_LGSSPARE1";
28"NC_CPU1_LGSSPARE2";
29"NC_CPU1_LGSSPARE3";
30"H_CPU1_RMCA_LVC1_R_N";
31"DBP_CPU1_HOOK9_MBP3_GTL_QS_R_N";
32"DBP_CPU1_HOOK8_MBP2_GTL_QS_R_N";
33"DBP_CPU1_MBP1_GTL_R_N";
34"DBP_CPU1_MBP0_GTL_R_N";
35"TP_CPU1_IFST_TRIG_LVC1_R";
36"TP_CPU1_IFST_KOT_LVC1_R";
37"TP_CPU1_IFST_DONE_LVC1_R";
38"DBP_CPU_MBP1_GTL_N";
39"DBP_CPU_MBP0_GTL_N";
40"DBP_CPU_HOOK8_MBP2_GTL_QS_N";
41"DBP_CPU_HOOK9_MBP3_GTL_QS_N";
%"SOCKET4677_AZIF0045P001C01CS"
"4","(-450,4875)","0","pure_quanta","I16";
;
PART_NUMBER"DGA^7000023"
PART_TYPE"SMLF"
MATERIAL"IO"
VALUE"SOCKET4677_AZIF0045-P001C01CS"
$LOCATION"U1"
CDS_LIB"pure_quanta"
NEEDS_NO_SIZE"TRUE"
CDS_LMAN_SYM_OUTLINE"-1100,850,1050,-850"
CDS_LOCATION"U1"
$SEC"4"
CDS_SEC"4";
"VSS_VCCIN_SENSE"
$PN"BC90"20;
"VSS_VCCINFAON_SENSE"
$PN"CE11"19;
"VSS_VCCFA_EHV_SENSE"
$PN"BA11"18;
"VSS_VCCFA_EHV_FIVRA_SENSE"
$PN"AT85"17;
"VSS_VCCD_HV_SENSE"
$PN"BN11"16;
"VCCIN_SENSE"
$PN"BD87"15;
"VCCINFAON_SENSE"
$PN"CA11"14;
"VCCFA_EHV_SENSE"
$PN"AU11"13;
"VCCFA_EHV_FIVRA_SENSE"
$PN"AY85"12;
"VCCD_HV_SENSE"
$PN"BU11"11;
"RSVD81"
$PN"CC64"21;
"RSVD9"
$PN"AU56"10;
"RSVD7"
$PN"AU33"9;
"RSVD18"
$PN"AV40"22;
"RSVD17"
$PN"AV38"23;
"RSVD16"
$PN"AV32"8;
"RSVD162"
$PN"H12"24;
"RSVD158"
$PN"DA45"3;
"RSVD153"
$PN"CY49"4;
"RSVD152"
$PN"CY38"2;
"RSVD151"
$PN"CY24"7;
"RSVD134"
$PN"CR60"25;
"RSVD129"
$PN"CP61"26;
"RSVD125"
$PN"CN60"27;
"RSVD139"
$PN"CU62"28;
"RSVD90"
$PN"CE62"29;
"RSVD10"
$PN"AU58"6;
"RMCA_N \B"
$PN"BH22"30;
"PMAX_TRIGGER_IO"
$PN"BD24"5;
"MBP3_N \B"
$PN"BK24"31;
"MBP2_N \B"
$PN"BJ23"32;
"MBP1_N \B"
$PN"BN25"33;
"MBP0_N \B"
$PN"BL23"34;
"RSVD49"
$PN"BF24"35;
"RSVD46"
$PN"BE23"36;
"RSVD37"
$PN"BC23"37;
%"Q_RES"
"1","(2250,4475)","0","pure_quanta","I22";
;
PART_NUMBER"CS01002FB07"
WATTAGE"1/16W"
PACK_TYPE"0402LF"
MATERIAL"CHIP"
VALUE"10"
TOLERANCE"1%"
$LOCATION"R54"
CDS_LIB"pure_quanta"
$LOCATION"R54"
CDS_LOCATION"R54"
$SEC"1"
CDS_SEC"1";
"B"
$PN"2"41;
"A"
$PN"1"31;
%"Q_RES"
"1","(2250,4525)","0","pure_quanta","I23";
;
PART_NUMBER"CS01002FB07"
WATTAGE"1/16W"
PACK_TYPE"0402LF"
VALUE"10"
TOLERANCE"1%"
MATERIAL"CHIP"
$LOCATION"R53"
CDS_LIB"pure_quanta"
$LOCATION"R53"
CDS_LOCATION"R53"
$SEC"1"
CDS_SEC"1";
"B"
$PN"2"40;
"A"
$PN"1"32;
%"Q_RES"
"1","(2250,4625)","0","pure_quanta","I24";
;
PART_NUMBER"CS11002FB07"
WATTAGE"1/16W"
PACK_TYPE"0402LF"
TOLERANCE"1%"
VALUE"100"
MATERIAL"CHIP"
$LOCATION"R51"
CDS_LIB"pure_quanta"
$LOCATION"R51"
CDS_LOCATION"R51"
$SEC"1"
CDS_SEC"1";
"B"
$PN"2"39;
"A"
$PN"1"34;
%"Q_RES"
"1","(2250,4575)","0","pure_quanta","I25";
;
PART_NUMBER"CS11002FB07"
WATTAGE"1/16W"
PACK_TYPE"0402LF"
VALUE"100"
TOLERANCE"1%"
MATERIAL"CHIP"
$LOCATION"R52"
CDS_LIB"pure_quanta"
$LOCATION"R52"
CDS_LOCATION"R52"
$SEC"1"
CDS_SEC"1";
"B"
$PN"2"38;
"A"
$PN"1"33;
%"Q_RES"
"2","(3675,4975)","0","pure_quanta","I34";
;
PART_NUMBER"CS14992FB06"
WATTAGE"1/16W"
PACK_TYPE"0402LF"
TOLERANCE"1%"
VALUE"499"
MATERIAL"CHIP"
$LOCATION"R49"
CDS_LIB"pure_quanta"
$LOCATION"R49"
CDS_LOCATION"R49"
$SEC"1"
CDS_SEC"1";
"A"
$PN"1"1;
"B"
$PN"2"39;
%"Q_RES"
"2","(3925,4975)","0","pure_quanta","I35";
;
PART_NUMBER"CS14992FB06"
MATERIAL"CHIP"
TOLERANCE"1%"
PACK_TYPE"0402LF"
WATTAGE"1/16W"
VALUE"499"
$LOCATION"R50"
CDS_LIB"pure_quanta"
$LOCATION"R50"
CDS_LOCATION"R50"
$SEC"1"
CDS_SEC"1";
"A"
$PN"1"1;
"B"
$PN"2"38;
%"UNIVERSAL_POWER"
"1","(3675,5300)","0","logical_power","I36";
;
HDL_POWER"PVNN_TERM_CPU1"
CDS_LIB"logical_power";
"A"1;
END.
